# T6G (Grand Teton) — schematic parts with pin connectivity, parts 8081–8081 of 8303; source: Cadence DE-HDL packaged netlist (pstxprt.dat, pstxnet.dat, pstchip.dat)

U25  GENOA_SP5  SOCKET6096_13568-001 IO  pkg SOCKET6096_93-4X120-45XA  page 10  (pins 5041-5376 of 6096)
  F26  VSS_F26  POWER  = GND
  F27  VSS_F27  POWER  = GND
  F28  VDDCR_CPU0_F28  POWER  = PVDDCR_CPU0_P0
  F29  VSS_F29  POWER  = GND
  F30  VSS_F30  POWER  = GND
  F31  VDDCR_CPU0_F31  POWER  = PVDDCR_CPU0_P0
  F32  VSS_F32  POWER  = GND
  F33  VSS_F33  POWER  = GND
  F34  VDDCR_CPU0_F34  POWER  = PVDDCR_CPU0_P0
  F35  VSS_F35  POWER  = GND
  F36  VSS_F36  POWER  = GND
  F37  VSS_F37  POWER  = GND
  F39  VSS_F39  POWER  = GND
  F40  VSS_F40  POWER  = GND
  F41  VSS_F41  POWER  = GND
  F42  VDDCR_CPU0_F42  POWER  = PVDDCR_CPU0_P0
  F43  VSS_F43  POWER  = GND
  F44  VSS_F44  POWER  = GND
  F45  VDDCR_CPU0_F45  POWER  = PVDDCR_CPU0_P0
  F46  VSS_F46  POWER  = GND
  F47  VSS_F47  POWER  = GND
  F48  VDDCR_CPU0_F48  POWER  = PVDDCR_CPU0_P0
  F49  VSS_F49  POWER  = GND
  F50  VSS_F50  POWER  = GND
  F51  VDDCR_CPU0_F51  POWER  = PVDDCR_CPU0_P0
  F52  VSS_F52  POWER  = GND
  F53  VSS_F53  POWER  = GND
  F54  VDDCR_CPU0_F54  POWER  = PVDDCR_CPU0_P0
  F55  MCA_DATA1  BI  = M_C_CPU0_SA_DQ<1>
  F56  MCA_DATA2  BI  = M_C_CPU0_SA_DQ<2>
  F57  VSS_F57  POWER  = GND
  F58  MDA_DATA1  BI  = M_D_CPU0_SA_DQ<1>
  F59  VSS_F59  POWER  = GND
  F60  MDA_DATA2  BI  = M_D_CPU0_SA_DQ<2>
  F61  VSS_F61  POWER  = GND
  F62  MBA_DATA1  BI  = M_B_CPU0_SA_DQ<1>
  F63  MBA_DATA2  BI  = M_B_CPU0_SA_DQ<2>
  F64  VSS_F64  POWER  = GND
  F65  MFA_DATA1  BI  = M_F_CPU0_SA_DQ<1>
  F66  VSS_F66  POWER  = GND
  F67  MFA_DATA2  BI  = M_F_CPU0_SA_DQ<2>
  F68  VSS_F68  POWER  = GND
  F69  MEA_DATA1  BI  = M_E_CPU0_SA_DQ<1>
  F70  MEA_DATA2  BI  = M_E_CPU0_SA_DQ<2>
  F71  VSS_F71  POWER  = GND
  F72  MAA_DATA1  BI  = M_A_CPU0_SA_DQ<1>
  F73  VSS_F73  POWER  = GND
  F74  MAA_DATA2  BI  = M_A_CPU0_SA_DQ<2>
  G1  VSS_G1  POWER  = GND
  G2  MGA_DQS_H0  BI  = M_G_CPU0_SA_DQS_DP<0>
  G3  MGA_DATA3  BI  = M_G_CPU0_SA_DQ<3>
  G4  VSS_G4  POWER  = GND
  G5  MKA_DQS_H0  BI  = M_K_CPU0_SA_DQS_DP<0>
  G6  VSS_G6  POWER  = GND
  G7  MKA_DATA3  BI  = M_K_CPU0_SA_DQ<3>
  G8  VSS_G8  POWER  = GND
  G9  MLA_DQS_H0  BI  = M_L_CPU0_SA_DQS_DP<0>
  G10  MLA_DATA3  BI  = M_L_CPU0_SA_DQ<3>
  G11  VSS_G11  POWER  = GND
  G12  MHA_DQS_H0  BI  = M_H_CPU0_SA_DQS_DP<0>
  G13  VSS_G13  POWER  = GND
  G14  MHA_DATA3  BI  = M_H_CPU0_SA_DQ<3>
  G15  VSS_G15  POWER  = GND
  G16  MJA_DQS_H0  BI  = M_J_CPU0_SA_DQS_DP<0>
  G17  MJA_DATA3  BI  = M_J_CPU0_SA_DQ<3>
  G18  VSS_G18  POWER  = GND
  G19  MIA_DQS_H0  BI  = M_I_CPU0_SA_DQS_DP<0>
  G20  VSS_G20  POWER  = GND
  G21  MIA_DATA3  BI  = M_I_CPU0_SA_DQ<3>
  G22  VSS_G22  POWER  = GND
  G23  G2_TXP2  OUT  = GMI_CPU0_G2_CPU1_G0_TX_DP<2>
  G24  G2_TXN2  OUT  = GMI_CPU0_G2_CPU1_G0_TX_DN<2>
  G25  VSS_G25  POWER  = GND
  G26  G2_TXP5  OUT  = GMI_CPU0_G2_CPU1_G0_TX_DP<5>
  G27  G2_TXN5  OUT  = GMI_CPU0_G2_CPU1_G0_TX_DN<5>
  G28  VSS_G28  POWER  = GND
  G29  G2_TXP8  OUT  = GMI_CPU0_G2_CPU1_G0_TX_DP<8>
  G30  G2_TXN8  OUT  = GMI_CPU0_G2_CPU1_G0_TX_DN<8>
  G31  VSS_G31  POWER  = GND
  G32  G2_TXP11  OUT  = GMI_CPU0_G2_CPU1_G0_TX_DP<11>
  G33  G2_TXN11  OUT  = GMI_CPU0_G2_CPU1_G0_TX_DN<11>
  G34  VSS_G34  POWER  = GND
  G35  VDDCR_CPU0_G35  POWER  = PVDDCR_CPU0_P0
  G36  VDDCR_CPU0_G36  POWER  = PVDDCR_CPU0_P0
  G40  VDDCR_CPU0_G40  POWER  = PVDDCR_CPU0_P0
  G41  VDDCR_CPU0_G41  POWER  = PVDDCR_CPU0_P0
  G42  VSS_G42  POWER  = GND
  G43  G0_RXN4  IN  = GMI_CPU1_G2_CPU0_G0_TX_DN<4>
  G44  G0_RXP4  IN  = GMI_CPU1_G2_CPU0_G0_TX_DP<4>
  G45  VSS_G45  POWER  = GND
  G46  G0_RXN7  IN  = GMI_CPU1_G2_CPU0_G0_TX_DN<7>
  G47  G0_RXP7  IN  = GMI_CPU1_G2_CPU0_G0_TX_DP<7>
  G48  VSS_G48  POWER  = GND
  G49  G0_RXN10  IN  = GMI_CPU1_G2_CPU0_G0_TX_DN<10>
  G50  G0_RXP10  IN  = GMI_CPU1_G2_CPU0_G0_TX_DP<10>
  G51  VSS_G51  POWER  = GND
  G52  G0_RXN13  IN  = GMI_CPU1_G2_CPU0_G0_TX_DN<13>
  G53  G0_RXP13  IN  = GMI_CPU1_G2_CPU0_G0_TX_DP<13>
  G54  VSS_G54  POWER  = GND
  G55  MCA_DATA3  BI  = M_C_CPU0_SA_DQ<3>
  G56  VSS_G56  POWER  = GND
  G57  MCA_DQS_H0  BI  = M_C_CPU0_SA_DQS_DP<0>
  G58  VSS_G58  POWER  = GND
  G59  MDA_DATA3  BI  = M_D_CPU0_SA_DQ<3>
  G60  MDA_DQS_H0  BI  = M_D_CPU0_SA_DQS_DP<0>
  G61  VSS_G61  POWER  = GND
  G62  MBA_DATA3  BI  = M_B_CPU0_SA_DQ<3>
  G63  VSS_G63  POWER  = GND
  G64  MBA_DQS_H0  BI  = M_B_CPU0_SA_DQS_DP<0>
  G65  VSS_G65  POWER  = GND
  G66  MFA_DATA3  BI  = M_F_CPU0_SA_DQ<3>
  G67  MFA_DQS_H0  BI  = M_F_CPU0_SA_DQS_DP<0>
  G68  VSS_G68  POWER  = GND
  G69  MEA_DATA3  BI  = M_E_CPU0_SA_DQ<3>
  G70  VSS_G70  POWER  = GND
  G71  MEA_DQS_H0  BI  = M_E_CPU0_SA_DQS_DP<0>
  G72  VSS_G72  POWER  = GND
  G73  MAA_DATA3  BI  = M_A_CPU0_SA_DQ<3>
  G74  MAA_DQS_H0  BI  = M_A_CPU0_SA_DQS_DP<0>
  G75  VSS_G75  POWER  = GND
  H2  MGA_DQS_L0  BI  = M_G_CPU0_SA_DQS_DN<0>
  H3  VSS_H3  POWER  = GND
  H4  MGA_DQS_L5  BI  = M_G_CPU0_SA_DQS_DN<5>
  H5  VDDCR_SOC_H5  POWER  = PVDDCR_SOC_P0
  H6  MKA_DQS_L0  BI  = M_K_CPU0_SA_DQS_DN<0>
  H7  MKA_DQS_L5  BI  = M_K_CPU0_SA_DQS_DN<5>
  H8  VSS_H8  POWER  = GND
  H9  MLA_DQS_L0  BI  = M_L_CPU0_SA_DQS_DN<0>
  H10  VSS_H10  POWER  = GND
  H11  MLA_DQS_L5  BI  = M_L_CPU0_SA_DQS_DN<5>
  H12  VDDCR_SOC_H12  POWER  = PVDDCR_SOC_P0
  H13  MHA_DQS_L0  BI  = M_H_CPU0_SA_DQS_DN<0>
  H14  MHA_DQS_L5  BI  = M_H_CPU0_SA_DQS_DN<5>
  H15  VSS_H15  POWER  = GND
  H16  MJA_DQS_L0  BI  = M_J_CPU0_SA_DQS_DN<0>
  H17  VSS_H17  POWER  = GND
  H18  MJA_DQS_L5  BI  = M_J_CPU0_SA_DQS_DN<5>
  H19  VDDCR_SOC_H19  POWER  = PVDDCR_SOC_P0
  H20  MIA_DQS_L0  BI  = M_I_CPU0_SA_DQS_DN<0>
  H21  MIA_DQS_L5  BI  = M_I_CPU0_SA_DQS_DN<5>
  H22  VSS_H22  POWER  = GND
  H23  VDDCR_CPU0_H23  POWER  = PVDDCR_CPU0_P0
  H24  VDDCR_CPU0_H24  POWER  = PVDDCR_CPU0_P0
  H25  VSS_H25  POWER  = GND
  H26  VDDCR_CPU0_H26  POWER  = PVDDCR_CPU0_P0
  H27  VDDCR_CPU0_H27  POWER  = PVDDCR_CPU0_P0
  H28  VSS_H28  POWER  = GND
  H29  VDDCR_CPU0_H29  POWER  = PVDDCR_CPU0_P0
  H30  VDDCR_CPU0_H30  POWER  = PVDDCR_CPU0_P0
  H31  VSS_H31  POWER  = GND
  H32  VDDCR_CPU0_H32  POWER  = PVDDCR_CPU0_P0
  H33  VDDCR_CPU0_H33  POWER  = PVDDCR_CPU0_P0
  H34  VSS_H34  POWER  = GND
  H35  G2_TXP13  OUT  = GMI_CPU0_G2_CPU1_G0_TX_DP<13>
  H36  G2_TXN13  OUT  = GMI_CPU0_G2_CPU1_G0_TX_DN<13>
  H37  VSS_H37  POWER  = GND
  H39  VSS_H39  POWER  = GND
  H40  G0_RXN2  IN  = GMI_CPU1_G2_CPU0_G0_TX_DN<2>
  H41  G0_RXP2  IN  = GMI_CPU1_G2_CPU0_G0_TX_DP<2>
  H42  VSS_H42  POWER  = GND
  H43  VDDCR_CPU0_H43  POWER  = PVDDCR_CPU0_P0
  H44  VDDCR_CPU0_H44  POWER  = PVDDCR_CPU0_P0
  H45  VSS_H45  POWER  = GND
  H46  VDDCR_CPU0_H46  POWER  = PVDDCR_CPU0_P0
  H47  VDDCR_CPU0_H47  POWER  = PVDDCR_CPU0_P0
  H48  VSS_H48  POWER  = GND
  H49  VDDCR_CPU0_H49  POWER  = PVDDCR_CPU0_P0
  H50  VDDCR_CPU0_H50  POWER  = PVDDCR_CPU0_P0
  H51  VSS_H51  POWER  = GND
  H52  VDDCR_CPU0_H52  POWER  = PVDDCR_CPU0_P0
  H53  VDDCR_CPU0_H53  POWER  = PVDDCR_CPU0_P0
  H54  VSS_H54  POWER  = GND
  H55  MCA_DQS_L5  BI  = M_C_CPU0_SA_DQS_DN<5>
  H56  MCA_DQS_L0  BI  = M_C_CPU0_SA_DQS_DN<0>
  H57  VDDIO_H57  POWER  = PVDDIO_P0
  H58  MDA_DQS_L5  BI  = M_D_CPU0_SA_DQS_DN<5>
  H59  VSS_H59  POWER  = GND
  H60  MDA_DQS_L0  BI  = M_D_CPU0_SA_DQS_DN<0>
  H61  VSS_H61  POWER  = GND
  H62  MBA_DQS_L5  BI  = M_B_CPU0_SA_DQS_DN<5>
  H63  MBA_DQS_L0  BI  = M_B_CPU0_SA_DQS_DN<0>
  H64  VDDIO_H64  POWER  = PVDDIO_P0
  H65  MFA_DQS_L5  BI  = M_F_CPU0_SA_DQS_DN<5>
  H66  VSS_H66  POWER  = GND
  H67  MFA_DQS_L0  BI  = M_F_CPU0_SA_DQS_DN<0>
  H68  VSS_H68  POWER  = GND
  H69  MEA_DQS_L5  BI  = M_E_CPU0_SA_DQS_DN<5>
  H70  MEA_DQS_L0  BI  = M_E_CPU0_SA_DQS_DN<0>
  H71  VDDIO_H71  POWER  = PVDDIO_P0
  H72  MAA_DQS_L5  BI  = M_A_CPU0_SA_DQS_DN<5>
  H73  VSS_H73  POWER  = GND
  H74  MAA_DQS_L0  BI  = M_A_CPU0_SA_DQS_DN<0>
  J1  VSS_J1  POWER  = GND
  J2  MGA_DATA4  BI  = M_G_CPU0_SA_DQ<4>
  J3  MGA_DQS_H5  BI  = M_G_CPU0_SA_DQS_DP<5>
  J4  VSS_J4  POWER  = GND
  J5  MKA_DATA4  BI  = M_K_CPU0_SA_DQ<4>
  J6  VSS_J6  POWER  = GND
  J7  MKA_DQS_H5  BI  = M_K_CPU0_SA_DQS_DP<5>
  J8  VSS_J8  POWER  = GND
  J9  MLA_DATA4  BI  = M_L_CPU0_SA_DQ<4>
  J10  MLA_DQS_H5  BI  = M_L_CPU0_SA_DQS_DP<5>
  J11  VSS_J11  POWER  = GND
  J12  MHA_DATA4  BI  = M_H_CPU0_SA_DQ<4>
  J13  VSS_J13  POWER  = GND
  J14  MHA_DQS_H5  BI  = M_H_CPU0_SA_DQS_DP<5>
  J15  VSS_J15  POWER  = GND
  J16  MJA_DATA4  BI  = M_J_CPU0_SA_DQ<4>
  J17  MJA_DQS_H5  BI  = M_J_CPU0_SA_DQS_DP<5>
  J18  VSS_J18  POWER  = GND
  J19  MIA_DATA4  BI  = M_I_CPU0_SA_DQ<4>
  J20  VSS_J20  POWER  = GND
  J21  MIA_DQS_H5  BI  = M_I_CPU0_SA_DQS_DP<5>
  J22  VSS_J22  POWER  = GND
  J23  G2_TXP1  OUT  = GMI_CPU0_G2_CPU1_G0_TX_DP<1>
  J24  G2_TXN1  OUT  = GMI_CPU0_G2_CPU1_G0_TX_DN<1>
  J25  VSS_J25  POWER  = GND
  J26  G2_TXP4  OUT  = GMI_CPU0_G2_CPU1_G0_TX_DP<4>
  J27  G2_TXN4  OUT  = GMI_CPU0_G2_CPU1_G0_TX_DN<4>
  J28  VSS_J28  POWER  = GND
  J29  G2_TXP7  OUT  = GMI_CPU0_G2_CPU1_G0_TX_DP<7>
  J30  G2_TXN7  OUT  = GMI_CPU0_G2_CPU1_G0_TX_DN<7>
  J31  VSS_J31  POWER  = GND
  J32  G2_TXP10  OUT  = GMI_CPU0_G2_CPU1_G0_TX_DP<10>
  J33  G2_TXN10  OUT  = GMI_CPU0_G2_CPU1_G0_TX_DN<10>
  J34  VSS_J34  POWER  = GND
  J35  VDDCR_CPU0_J35  POWER  = PVDDCR_CPU0_P0
  J36  VDDCR_CPU0_J36  POWER  = PVDDCR_CPU0_P0
  J40  VDDCR_CPU0_J40  POWER  = PVDDCR_CPU0_P0
  J41  VDDCR_CPU0_J41  POWER  = PVDDCR_CPU0_P0
  J42  VSS_J42  POWER  = GND
  J43  G0_RXN5  IN  = GMI_CPU1_G2_CPU0_G0_TX_DN<5>
  J44  G0_RXP5  IN  = GMI_CPU1_G2_CPU0_G0_TX_DP<5>
  J45  VSS_J45  POWER  = GND
  J46  G0_RXN8  IN  = GMI_CPU1_G2_CPU0_G0_TX_DN<8>
  J47  G0_RXP8  IN  = GMI_CPU1_G2_CPU0_G0_TX_DP<8>
  J48  VSS_J48  POWER  = GND
  J49  G0_RXN11  IN  = GMI_CPU1_G2_CPU0_G0_TX_DN<11>
  J50  G0_RXP11  IN  = GMI_CPU1_G2_CPU0_G0_TX_DP<11>
  J51  VSS_J51  POWER  = GND
  J52  G0_RXN14  IN  = GMI_CPU1_G2_CPU0_G0_TX_DN<14>
  J53  G0_RXP14  IN  = GMI_CPU1_G2_CPU0_G0_TX_DP<14>
  J54  VSS_J54  POWER  = GND
  J55  MCA_DQS_H5  BI  = M_C_CPU0_SA_DQS_DP<5>
  J56  VSS_J56  POWER  = GND
  J57  MCA_DATA4  BI  = M_C_CPU0_SA_DQ<4>
  J58  VSS_J58  POWER  = GND
  J59  MDA_DQS_H5  BI  = M_D_CPU0_SA_DQS_DP<5>
  J60  MDA_DATA4  BI  = M_D_CPU0_SA_DQ<4>
  J61  VSS_J61  POWER  = GND
  J62  MBA_DQS_H5  BI  = M_B_CPU0_SA_DQS_DP<5>
  J63  VSS_J63  POWER  = GND
  J64  MBA_DATA4  BI  = M_B_CPU0_SA_DQ<4>
  J65  VSS_J65  POWER  = GND
  J66  MFA_DQS_H5  BI  = M_F_CPU0_SA_DQS_DP<5>
  J67  MFA_DATA4  BI  = M_F_CPU0_SA_DQ<4>
  J68  VSS_J68  POWER  = GND
  J69  MEA_DQS_H5  BI  = M_E_CPU0_SA_DQS_DP<5>
  J70  VSS_J70  POWER  = GND
  J71  MEA_DATA4  BI  = M_E_CPU0_SA_DQ<4>
  J72  VSS_J72  POWER  = GND
  J73  MAA_DQS_H5  BI  = M_A_CPU0_SA_DQS_DP<5>
  J74  MAA_DATA4  BI  = M_A_CPU0_SA_DQ<4>
  J75  VSS_J75  POWER  = GND
  K2  MGA_DATA6  BI  = M_G_CPU0_SA_DQ<6>
  K3  VSS_K3  POWER  = GND
  K4  MGA_DATA5  BI  = M_G_CPU0_SA_DQ<5>
  K5  VSS_K5  POWER  = GND
  K6  MKA_DATA6  BI  = M_K_CPU0_SA_DQ<6>
  K7  MKA_DATA5  BI  = M_K_CPU0_SA_DQ<5>
  K8  VSS_K8  POWER  = GND
  K9  MLA_DATA6  BI  = M_L_CPU0_SA_DQ<6>
  K10  VSS_K10  POWER  = GND
  K11  MLA_DATA5  BI  = M_L_CPU0_SA_DQ<5>
  K12  VSS_K12  POWER  = GND
  K13  MHA_DATA6  BI  = M_H_CPU0_SA_DQ<6>
  K14  MHA_DATA5  BI  = M_H_CPU0_SA_DQ<5>
  K15  VSS_K15  POWER  = GND
  K16  MJA_DATA6  BI  = M_J_CPU0_SA_DQ<6>
  K17  VSS_K17  POWER  = GND
  K18  MJA_DATA5  BI  = M_J_CPU0_SA_DQ<5>
  K19  VSS_K19  POWER  = GND
  K20  MIA_DATA6  BI  = M_I_CPU0_SA_DQ<6>
  K21  MIA_DATA5  BI  = M_I_CPU0_SA_DQ<5>
  K22  VDDCR_SOC_K22  POWER  = PVDDCR_SOC_P0
  K23  VSS_K23  POWER  = GND
  K24  VSS_K24  POWER  = GND
  K25  VSS_K25  POWER  = GND
  K26  VSS_K26  POWER  = GND
  K27  VSS_K27  POWER  = GND
  K28  VSS_K28  POWER  = GND
  K29  VSS_K29  POWER  = GND
  K30  VSS_K30  POWER  = GND
  K31  VSS_K31  POWER  = GND
  K32  VSS_K32  POWER  = GND
  K33  VSS_K33  POWER  = GND
  K34  VSS_K34  POWER  = GND
  K35  G2_TXP14  OUT  = GMI_CPU0_G2_CPU1_G0_TX_DP<14>
  K36  G2_TXN14  OUT  = GMI_CPU0_G2_CPU1_G0_TX_DN<14>
  K37  VSS_K37  POWER  = GND
  K39  VSS_K39  POWER  = GND
  K40  G0_RXN1  IN  = GMI_CPU1_G2_CPU0_G0_TX_DN<1>
  K41  G0_RXP1  IN  = GMI_CPU1_G2_CPU0_G0_TX_DP<1>
  K42  VSS_K42  POWER  = GND
  K43  VSS_K43  POWER  = GND
  K44  VSS_K44  POWER  = GND
  K45  VSS_K45  POWER  = GND
  K46  VSS_K46  POWER  = GND
  K47  VSS_K47  POWER  = GND
  K48  VSS_K48  POWER  = GND
  K49  VSS_K49  POWER  = GND
  K50  VSS_K50  POWER  = GND
  K51  VSS_K51  POWER  = GND
  K52  VSS_K52  POWER  = GND
  K53  VSS_K53  POWER  = GND
  K54  VDDIO_K54  POWER  = PVDDIO_P0
  K55  MCA_DATA5  BI  = M_C_CPU0_SA_DQ<5>
  K56  MCA_DATA6  BI  = M_C_CPU0_SA_DQ<6>
  K57  VSS_K57  POWER  = GND
  K58  MDA_DATA5  BI  = M_D_CPU0_SA_DQ<5>
  K59  VSS_K59  POWER  = GND
  K60  MDA_DATA6  BI  = M_D_CPU0_SA_DQ<6>
  K61  VSS_K61  POWER  = GND
  K62  MBA_DATA5  BI  = M_B_CPU0_SA_DQ<5>
  K63  MBA_DATA6  BI  = M_B_CPU0_SA_DQ<6>
  K64  VSS_K64  POWER  = GND
  K65  MFA_DATA5  BI  = M_F_CPU0_SA_DQ<5>
  K66  VSS_K66  POWER  = GND
  K67  MFA_DATA6  BI  = M_F_CPU0_SA_DQ<6>
  K68  VSS_K68  POWER  = GND
  K69  MEA_DATA5  BI  = M_E_CPU0_SA_DQ<5>
  K70  MEA_DATA6  BI  = M_E_CPU0_SA_DQ<6>
  K71  VSS_K71  POWER  = GND
  K72  MAA_DATA5  BI  = M_A_CPU0_SA_DQ<5>
  K73  VSS_K73  POWER  = GND
  K74  MAA_DATA6  BI  = M_A_CPU0_SA_DQ<6>
